(kicad_pcb
	(version 20260206)
	(generator "pcbnew")
	(generator_version "10.0")
	(general
		(thickness 1.6)
		(legacy_teardrops no)
	)
	(paper "A4")
	(title_block
		(title "03242023_DA0F0TMBIJ0_F0T_Motherboard_J_brd_V01_OCP.brd")
		(comment 1 "Grand Teton / footprints 3306-3311 of 6105")
	)
	(layers
		(0 "F.Cu" signal "TOP")
		(4 "In1.Cu" signal "GND")
		(6 "In2.Cu" signal "IN1")
		(8 "In3.Cu" signal "GND1")
		(10 "In4.Cu" signal "IN2")
		(12 "In5.Cu" signal "GND2")
		(14 "In6.Cu" signal "IN3")
		(16 "In7.Cu" signal "GND3")
		(18 "In8.Cu" signal "VCC")
		(20 "In9.Cu" signal "VCC1")
		(22 "In10.Cu" signal "GND4")
		(24 "In11.Cu" signal "IN4")
		(26 "In12.Cu" signal "GND5")
		(28 "In13.Cu" signal "IN5")
		(30 "In14.Cu" signal "GND6")
		(32 "In15.Cu" signal "IN6")
		(34 "In16.Cu" signal "GND7")
		(2 "B.Cu" signal "BOTTOM")
		(9 "F.Adhes" user "F.Adhesive")
		(11 "B.Adhes" user "B.Adhesive")
		(13 "F.Paste" user "Package Geometry/Pastemask Top")
		(15 "B.Paste" user "Package Geometry/Pastemask Bottom")
		(5 "F.SilkS" user "Ref Des/Silkscreen Top")
		(7 "B.SilkS" user "Ref Des/Silkscreen Bottom")
		(1 "F.Mask" user "Board Geometry/Soldermask Top")
		(3 "B.Mask" user "Board Geometry/Soldermask Bottom")
		(17 "Dwgs.User" user "User.Drawings")
		(19 "Cmts.User" user "User.Comments")
		(21 "Eco1.User" user "User.Eco1")
		(23 "Eco2.User" user "User.Eco2")
		(25 "Edge.Cuts" user "Board Geometry/Outline")
		(27 "Margin" user)
		(31 "F.CrtYd" user "Package Geometry/Place Bound Top")
		(29 "B.CrtYd" user "Package Geometry/Place Bound Bottom")
		(35 "F.Fab" user "Ref Des/Assembly Top")
		(33 "B.Fab" user "Ref Des/Assembly Bottom")
	)
	(footprint ""
		(layer "F.Cu")
		(at 75.523598 -402.371052 -90)
		(property "Reference" "C728"
			(at 0 0 270)
			(layer "F.SilkS")
			(hide yes)
			(effects
				(font
					(size 1.27 1.27)
				)
			)
		)
		(property "Value" ""
			(at 0 0 270)
			(layer "F.Fab")
			(effects
				(font
					(size 1.27 1.27)
				)
			)
		)
		(duplicate_pad_numbers_are_jumpers no)
		(fp_line
			(start -0.299974 0.150114)
			(end -0.299974 -0.150114)
			(stroke
				(width 0.1)
				(type default)
			)
			(layer "F.Fab")
		)
		(fp_line
			(start 0.299974 0.150114)
			(end -0.299974 0.150114)
			(stroke
				(width 0.1)
				(type default)
			)
			(layer "F.Fab")
		)
		(fp_line
			(start -0.299974 -0.150114)
			(end 0.299974 -0.150114)
			(stroke
				(width 0.1)
				(type default)
			)
			(layer "F.Fab")
		)
		(fp_line
			(start 0.299974 -0.150114)
			(end 0.299974 0.150114)
			(stroke
				(width 0.1)
				(type default)
			)
			(layer "F.Fab")
		)
		(pad "1" smd rect
			(at -0.2667 0 270)
			(size 0.3048 0.381)
			(layers "F.Cu" "F.Mask" "F.Paste")
			(net "P5E_CPU1_PE0_TX_C_DN<6>")
		)
		(pad "2" smd rect
			(at 0.2667 0 270)
			(size 0.3048 0.381)
			(layers "F.Cu" "F.Mask" "F.Paste")
			(net "P5E_CPU1_PE0_TX_DN<6>")
		)
	)
	(footprint ""
		(layer "F.Cu")
		(at 100.924614 -96.123506)
		(property "Reference" "Q87"
			(at 1.59766 -0.765048 0)
			(unlocked yes)
			(layer "F.SilkS")
			(effects
				(font
					(size 0.7874 0.5842)
					(thickness 0.1524)
				)
				(justify left)
			)
		)
		(property "Value" ""
			(at 0 0 0)
			(layer "F.Fab")
			(effects
				(font
					(size 1.27 1.27)
				)
			)
		)
		(duplicate_pad_numbers_are_jumpers no)
		(fp_line
			(start -1.332738 -1.100074)
			(end -0.4826 -1.100074)
			(stroke
				(width 0.1524)
				(type default)
			)
			(layer "F.SilkS")
		)
		(fp_line
			(start -1.332738 1.100074)
			(end -1.332738 -1.100074)
			(stroke
				(width 0.1524)
				(type default)
			)
			(layer "F.SilkS")
		)
		(fp_line
			(start -0.4826 -1.100074)
			(end 0 -0.541274)
			(stroke
				(width 0.1524)
				(type default)
			)
			(layer "F.SilkS")
		)
		(fp_line
			(start 0 -0.541274)
			(end 0.4826 -1.100074)
			(stroke
				(width 0.1524)
				(type default)
			)
			(layer "F.SilkS")
		)
		(fp_line
			(start 0.4826 -1.100074)
			(end 1.332738 -1.100074)
			(stroke
				(width 0.1524)
				(type default)
			)
			(layer "F.SilkS")
		)
		(fp_line
			(start 1.332738 -1.100074)
			(end 1.332738 1.100074)
			(stroke
				(width 0.1524)
				(type default)
			)
			(layer "F.SilkS")
		)
		(fp_line
			(start 1.332738 1.100074)
			(end -1.332738 1.100074)
			(stroke
				(width 0.1524)
				(type default)
			)
			(layer "F.SilkS")
		)
		(fp_poly
			(pts
				(xy -0.600202 -1.933448) (xy -0.95123 -1.231392) (xy -1.302258 -1.933448)
			)
			(stroke
				(width 0)
				(type default)
			)
			(fill yes)
			(layer "F.SilkS")
		)
		(fp_line
			(start -0.674878 -1.100074)
			(end 0.674878 -1.100074)
			(stroke
				(width 0.1)
				(type default)
			)
			(layer "F.Fab")
		)
		(fp_line
			(start -0.674878 1.100074)
			(end -0.674878 -1.100074)
			(stroke
				(width 0.1)
				(type default)
			)
			(layer "F.Fab")
		)
		(fp_line
			(start 0.674878 -1.100074)
			(end 0.674878 1.100074)
			(stroke
				(width 0.1)
				(type default)
			)
			(layer "F.Fab")
		)
		(fp_line
			(start 0.674878 1.100074)
			(end -0.674878 1.100074)
			(stroke
				(width 0.1)
				(type default)
			)
			(layer "F.Fab")
		)
		(fp_poly
			(pts
				(xy -2.2352 -0.298958) (xy -2.2352 -1.001014) (xy -1.533144 -0.649986)
			)
			(stroke
				(width 0)
				(type default)
			)
			(fill yes)
			(layer "F.Fab")
		)
		(pad "1" smd rect
			(at -0.94996 -0.649986 90)
			(size 0.4318 0.508)
			(layers "F.Cu" "F.Mask" "F.Paste")
			(net "GND")
		)
		(pad "2" smd rect
			(at -0.94996 0 90)
			(size 0.4318 0.508)
			(layers "F.Cu" "F.Mask" "F.Paste")
			(net "PWRGD_PCH_PWROK_R")
		)
		(pad "3" smd rect
			(at -0.94996 0.649986 90)
			(size 0.4318 0.508)
			(layers "F.Cu" "F.Mask" "F.Paste")
			(net "LED_PWRGD_SYS_PWROK_R_D")
		)
		(pad "4" smd rect
			(at 0.94996 0.649986 90)
			(size 0.4318 0.508)
			(layers "F.Cu" "F.Mask" "F.Paste")
			(net "GND")
		)
		(pad "5" smd rect
			(at 0.94996 0 90)
			(size 0.4318 0.508)
			(layers "F.Cu" "F.Mask" "F.Paste")
			(net "PWRGD_SYS_PWROK_R")
		)
		(pad "6" smd rect
			(at 0.94996 -0.649986 90)
			(size 0.4318 0.508)
			(layers "F.Cu" "F.Mask" "F.Paste")
			(net "LED_PWRGD_PCH_PWROK_R_D")
		)
	)
	(footprint ""
		(layer "F.Cu")
		(at 31.29788 -428.843948)
		(property "Reference" "R3467"
			(at 0 0 0)
			(layer "F.SilkS")
			(hide yes)
			(effects
				(font
					(size 1.27 1.27)
				)
			)
		)
		(property "Value" ""
			(at 0 0 0)
			(layer "F.Fab")
			(effects
				(font
					(size 1.27 1.27)
				)
			)
		)
		(duplicate_pad_numbers_are_jumpers no)
		(fp_line
			(start -0.7874 -0.4064)
			(end 0.7874 -0.4064)
			(stroke
				(width 0.1524)
				(type default)
			)
			(layer "F.SilkS")
		)
		(fp_line
			(start -0.7874 0.4064)
			(end -0.7874 -0.4064)
			(stroke
				(width 0.1524)
				(type default)
			)
			(layer "F.SilkS")
		)
		(fp_line
			(start 0.7874 -0.4064)
			(end 0.7874 0.4064)
			(stroke
				(width 0.1524)
				(type default)
			)
			(layer "F.SilkS")
		)
		(fp_line
			(start 0.7874 0.4064)
			(end -0.7874 0.4064)
			(stroke
				(width 0.1524)
				(type default)
			)
			(layer "F.SilkS")
		)
		(fp_line
			(start -0.67945 -0.305054)
			(end -0.12065 -0.305054)
			(stroke
				(width 0.1)
				(type default)
			)
			(layer "F.Fab")
		)
		(fp_line
			(start -0.67945 0.3048)
			(end -0.67945 -0.305054)
			(stroke
				(width 0.1)
				(type default)
			)
			(layer "F.Fab")
		)
		(fp_line
			(start -0.12065 -0.305054)
			(end -0.12065 -0.2794)
			(stroke
				(width 0.1)
				(type default)
			)
			(layer "F.Fab")
		)
		(fp_line
			(start -0.12065 -0.2794)
			(end 0.12065 -0.2794)
			(stroke
				(width 0.1)
				(type default)
			)
			(layer "F.Fab")
		)
		(fp_line
			(start -0.12065 0.2794)
			(end -0.12065 0.3048)
			(stroke
				(width 0.1)
				(type default)
			)
			(layer "F.Fab")
		)
		(fp_line
			(start -0.12065 0.3048)
			(end -0.67945 0.3048)
			(stroke
				(width 0.1)
				(type default)
			)
			(layer "F.Fab")
		)
		(fp_line
			(start 0.120396 0.2794)
			(end -0.12065 0.2794)
			(stroke
				(width 0.1)
				(type default)
			)
			(layer "F.Fab")
		)
		(fp_line
			(start 0.120396 0.3048)
			(end 0.120396 0.2794)
			(stroke
				(width 0.1)
				(type default)
			)
			(layer "F.Fab")
		)
		(fp_line
			(start 0.12065 -0.3048)
			(end 0.67945 -0.3048)
			(stroke
				(width 0.1)
				(type default)
			)
			(layer "F.Fab")
		)
		(fp_line
			(start 0.12065 -0.2794)
			(end 0.12065 -0.3048)
			(stroke
				(width 0.1)
				(type default)
			)
			(layer "F.Fab")
		)
		(fp_line
			(start 0.67945 -0.3048)
			(end 0.67945 0.3048)
			(stroke
				(width 0.1)
				(type default)
			)
			(layer "F.Fab")
		)
		(fp_line
			(start 0.67945 0.3048)
			(end 0.120396 0.3048)
			(stroke
				(width 0.1)
				(type default)
			)
			(layer "F.Fab")
		)
		(pad "1" smd circle
			(at -0.40005 0)
			(size 0 0)
			(layers "F.Cu" "F.Mask" "F.Paste")
			(net "RST_PERST_0_SWB_BUF_R_N")
		)
		(pad "2" smd circle
			(at 0.40005 0)
			(size 0 0)
			(layers "F.Cu" "F.Mask" "F.Paste")
			(net "GND")
		)
	)
	(footprint ""
		(layer "F.Cu")
		(at 300.99762 -413.756094 90)
		(property "Reference" "C2363"
			(at 0 0 90)
			(layer "F.SilkS")
			(hide yes)
			(effects
				(font
					(size 1.27 1.27)
				)
			)
		)
		(property "Value" ""
			(at 0 0 90)
			(layer "F.Fab")
			(effects
				(font
					(size 1.27 1.27)
				)
			)
		)
		(duplicate_pad_numbers_are_jumpers no)
		(fp_line
			(start 0.7874 -0.4064)
			(end 0.7874 0.4064)
			(stroke
				(width 0.1524)
				(type default)
			)
			(layer "F.SilkS")
		)
		(fp_line
			(start -0.7874 -0.4064)
			(end 0.7874 -0.4064)
			(stroke
				(width 0.1524)
				(type default)
			)
			(layer "F.SilkS")
		)
		(fp_line
			(start 0.7874 0.4064)
			(end -0.7874 0.4064)
			(stroke
				(width 0.1524)
				(type default)
			)
			(layer "F.SilkS")
		)
		(fp_line
			(start -0.7874 0.4064)
			(end -0.7874 -0.4064)
			(stroke
				(width 0.1524)
				(type default)
			)
			(layer "F.SilkS")
		)
		(fp_line
			(start -0.12065 -0.305054)
			(end -0.12065 -0.2794)
			(stroke
				(width 0.1)
				(type default)
			)
			(layer "F.Fab")
		)
		(fp_line
			(start -0.67945 -0.305054)
			(end -0.12065 -0.305054)
			(stroke
				(width 0.1)
				(type default)
			)
			(layer "F.Fab")
		)
		(fp_line
			(start 0.67945 -0.3048)
			(end 0.67945 0.3048)
			(stroke
				(width 0.1)
				(type default)
			)
			(layer "F.Fab")
		)
		(fp_line
			(start 0.12065 -0.3048)
			(end 0.67945 -0.3048)
			(stroke
				(width 0.1)
				(type default)
			)
			(layer "F.Fab")
		)
		(fp_line
			(start 0.12065 -0.2794)
			(end 0.12065 -0.3048)
			(stroke
				(width 0.1)
				(type default)
			)
			(layer "F.Fab")
		)
		(fp_line
			(start -0.12065 -0.2794)
			(end 0.12065 -0.2794)
			(stroke
				(width 0.1)
				(type default)
			)
			(layer "F.Fab")
		)
		(fp_line
			(start 0.120396 0.2794)
			(end -0.12065 0.2794)
			(stroke
				(width 0.1)
				(type default)
			)
			(layer "F.Fab")
		)
		(fp_line
			(start -0.12065 0.2794)
			(end -0.12065 0.3048)
			(stroke
				(width 0.1)
				(type default)
			)
			(layer "F.Fab")
		)
		(fp_line
			(start 0.67945 0.3048)
			(end 0.120396 0.3048)
			(stroke
				(width 0.1)
				(type default)
			)
			(layer "F.Fab")
		)
		(fp_line
			(start 0.120396 0.3048)
			(end 0.120396 0.2794)
			(stroke
				(width 0.1)
				(type default)
			)
			(layer "F.Fab")
		)
		(fp_line
			(start -0.12065 0.3048)
			(end -0.67945 0.3048)
			(stroke
				(width 0.1)
				(type default)
			)
			(layer "F.Fab")
		)
		(fp_line
			(start -0.67945 0.3048)
			(end -0.67945 -0.305054)
			(stroke
				(width 0.1)
				(type default)
			)
			(layer "F.Fab")
		)
		(pad "1" smd circle
			(at -0.40005 0 90)
			(size 0 0)
			(layers "F.Cu" "F.Mask" "F.Paste")
			(net "HSC_TYPE_ADC")
		)
		(pad "2" smd circle
			(at 0.40005 0 90)
			(size 0 0)
			(layers "F.Cu" "F.Mask" "F.Paste")
			(net "GND")
		)
	)
	(footprint ""
		(layer "F.Cu")
		(at 454.847452 -19.427698 -90)
		(property "Reference" "R3797"
			(at 0 0 270)
			(layer "F.SilkS")
			(hide yes)
			(effects
				(font
					(size 1.27 1.27)
				)
			)
		)
		(property "Value" ""
			(at 0 0 270)
			(layer "F.Fab")
			(effects
				(font
					(size 1.27 1.27)
				)
			)
		)
		(duplicate_pad_numbers_are_jumpers no)
		(fp_line
			(start -0.7874 0.4064)
			(end -0.7874 -0.4064)
			(stroke
				(width 0.1524)
				(type default)
			)
			(layer "F.SilkS")
		)
		(fp_line
			(start 0.7874 0.4064)
			(end -0.7874 0.4064)
			(stroke
				(width 0.1524)
				(type default)
			)
			(layer "F.SilkS")
		)
		(fp_line
			(start -0.7874 -0.4064)
			(end 0.7874 -0.4064)
			(stroke
				(width 0.1524)
				(type default)
			)
			(layer "F.SilkS")
		)
		(fp_line
			(start 0.7874 -0.4064)
			(end 0.7874 0.4064)
			(stroke
				(width 0.1524)
				(type default)
			)
			(layer "F.SilkS")
		)
		(fp_line
			(start -0.67945 0.3048)
			(end -0.67945 -0.305054)
			(stroke
				(width 0.1)
				(type default)
			)
			(layer "F.Fab")
		)
		(fp_line
			(start -0.12065 0.3048)
			(end -0.67945 0.3048)
			(stroke
				(width 0.1)
				(type default)
			)
			(layer "F.Fab")
		)
		(fp_line
			(start 0.120396 0.3048)
			(end 0.120396 0.2794)
			(stroke
				(width 0.1)
				(type default)
			)
			(layer "F.Fab")
		)
		(fp_line
			(start 0.67945 0.3048)
			(end 0.120396 0.3048)
			(stroke
				(width 0.1)
				(type default)
			)
			(layer "F.Fab")
		)
		(fp_line
			(start -0.12065 0.2794)
			(end -0.12065 0.3048)
			(stroke
				(width 0.1)
				(type default)
			)
			(layer "F.Fab")
		)
		(fp_line
			(start 0.120396 0.2794)
			(end -0.12065 0.2794)
			(stroke
				(width 0.1)
				(type default)
			)
			(layer "F.Fab")
		)
		(fp_line
			(start -0.12065 -0.2794)
			(end 0.12065 -0.2794)
			(stroke
				(width 0.1)
				(type default)
			)
			(layer "F.Fab")
		)
		(fp_line
			(start 0.12065 -0.2794)
			(end 0.12065 -0.3048)
			(stroke
				(width 0.1)
				(type default)
			)
			(layer "F.Fab")
		)
		(fp_line
			(start 0.12065 -0.3048)
			(end 0.67945 -0.3048)
			(stroke
				(width 0.1)
				(type default)
			)
			(layer "F.Fab")
		)
		(fp_line
			(start 0.67945 -0.3048)
			(end 0.67945 0.3048)
			(stroke
				(width 0.1)
				(type default)
			)
			(layer "F.Fab")
		)
		(fp_line
			(start -0.67945 -0.305054)
			(end -0.12065 -0.305054)
			(stroke
				(width 0.1)
				(type default)
			)
			(layer "F.Fab")
		)
		(fp_line
			(start -0.12065 -0.305054)
			(end -0.12065 -0.2794)
			(stroke
				(width 0.1)
				(type default)
			)
			(layer "F.Fab")
		)
		(pad "1" smd circle
			(at -0.40005 0 270)
			(size 0 0)
			(layers "F.Cu" "F.Mask" "F.Paste")
			(net "P3V3_AUX")
		)
		(pad "2" smd circle
			(at 0.40005 0 270)
			(size 0 0)
			(layers "F.Cu" "F.Mask" "F.Paste")
			(net "HP_LVC3_OCP_V3_1_P12V_PWRGD")
		)
	)
	(footprint ""
		(layer "F.Cu")
		(at 193.809366 -37.43325 90)
		(property "Reference" "Q39"
			(at -2.314702 -0.629158 0)
			(unlocked yes)
			(layer "F.SilkS")
			(effects
				(font
					(size 0.7874 0.5842)
					(thickness 0.1524)
				)
			)
		)
		(property "Value" ""
			(at 0 0 90)
			(layer "F.Fab")
			(effects
				(font
					(size 1.27 1.27)
				)
			)
		)
		(duplicate_pad_numbers_are_jumpers no)
		(fp_line
			(start 1.603248 -1.500124)
			(end 1.603248 1.500124)
			(stroke
				(width 0.1524)
				(type default)
			)
			(layer "F.SilkS")
		)
		(fp_line
			(start -1.603248 -1.500124)
			(end 1.603248 -1.500124)
			(stroke
				(width 0.1524)
				(type default)
			)
			(layer "F.SilkS")
		)
		(fp_line
			(start 1.603248 1.500124)
			(end -1.603248 1.500124)
			(stroke
				(width 0.1524)
				(type default)
			)
			(layer "F.SilkS")
		)
		(fp_line
			(start -1.603248 1.500124)
			(end -1.603248 -1.500124)
			(stroke
				(width 0.1524)
				(type default)
			)
			(layer "F.SilkS")
		)
		(fp_line
			(start 0.700024 -1.500124)
			(end -0.700024 -1.500124)
			(stroke
				(width 0.1)
				(type default)
			)
			(layer "F.Fab")
		)
		(fp_line
			(start -0.700024 -1.500124)
			(end -0.700024 -1.169924)
			(stroke
				(width 0.1)
				(type default)
			)
			(layer "F.Fab")
		)
		(fp_line
			(start -0.700024 -1.169924)
			(end -1.249934 -1.169924)
			(stroke
				(width 0.1)
				(type default)
			)
			(layer "F.Fab")
		)
		(fp_line
			(start -1.249934 -1.169924)
			(end -1.249934 -0.729996)
			(stroke
				(width 0.1)
				(type default)
			)
			(layer "F.Fab")
		)
		(fp_line
			(start -0.6985 -0.729996)
			(end -0.6985 0.729996)
			(stroke
				(width 0.1)
				(type default)
			)
			(layer "F.Fab")
		)
		(fp_line
			(start -1.249934 -0.729996)
			(end -0.6985 -0.729996)
			(stroke
				(width 0.1)
				(type default)
			)
			(layer "F.Fab")
		)
		(fp_line
			(start 1.249934 -0.219964)
			(end 0.700024 -0.219964)
			(stroke
				(width 0.1)
				(type default)
			)
			(layer "F.Fab")
		)
		(fp_line
			(start 0.700024 -0.219964)
			(end 0.700024 -1.500124)
			(stroke
				(width 0.1)
				(type default)
			)
			(layer "F.Fab")
		)
		(fp_line
			(start 1.249934 0.219964)
			(end 1.249934 -0.219964)
			(stroke
				(width 0.1)
				(type default)
			)
			(layer "F.Fab")
		)
		(fp_line
			(start 0.700024 0.219964)
			(end 1.249934 0.219964)
			(stroke
				(width 0.1)
				(type default)
			)
			(layer "F.Fab")
		)
		(fp_line
			(start -0.6985 0.729996)
			(end -1.249934 0.729996)
			(stroke
				(width 0.1)
				(type default)
			)
			(layer "F.Fab")
		)
		(fp_line
			(start -1.249934 0.729996)
			(end -1.249934 1.169924)
			(stroke
				(width 0.1)
				(type default)
			)
			(layer "F.Fab")
		)
		(fp_line
			(start -0.700024 1.169924)
			(end -0.700024 1.500124)
			(stroke
				(width 0.1)
				(type default)
			)
			(layer "F.Fab")
		)
		(fp_line
			(start -1.249934 1.169924)
			(end -0.700024 1.169924)
			(stroke
				(width 0.1)
				(type default)
			)
			(layer "F.Fab")
		)
		(fp_line
			(start 0.700024 1.500124)
			(end 0.700024 0.219964)
			(stroke
				(width 0.1)
				(type default)
			)
			(layer "F.Fab")
		)
		(fp_line
			(start -0.700024 1.500124)
			(end 0.700024 1.500124)
			(stroke
				(width 0.1)
				(type default)
			)
			(layer "F.Fab")
		)
		(fp_rect
			(start -0.700024 -1.500124)
			(end 0.700024 1.500124)
			(stroke
				(width 0)
				(type default)
			)
			(fill no)
			(layer "F.Fab")
		)
		(pad "D" smd rect
			(at 0.999998 0)
			(size 0.8128 0.9144)
			(layers "F.Cu" "F.Mask" "F.Paste")
			(net "P12V_SCM_EN")
		)
		(pad "G" smd rect
			(at -0.999998 -0.94996)
			(size 0.8128 0.9144)
			(layers "F.Cu" "F.Mask" "F.Paste")
			(net "FM_SCM_PRSNT1_R_N")
		)
		(pad "S" smd rect
			(at -0.999998 0.94996)
			(size 0.8128 0.9144)
			(layers "F.Cu" "F.Mask" "F.Paste")
			(net "GND")
		)
	)
)
